# T6G (Grand Teton) — schematic netlist excerpt (pin names and nets, part order shuffled) for the footprints in the layout excerpt that follows; sources: Cadence DE-HDL packaged netlist, KiCad conversion of 04192023_DAF0TMB3IC0_F0TG_MB_C_brd_V02_OCP.brd

R4181  Q_RES  33.2 1% CHIP  pkg 0402LF  page 235 : A = SMB_LM75_2_3V3AUX_SDA ; B = SMB_LM75_2_3V3AUX_SDA_R1

(kicad_pcb
	(version 20260206)
	(generator "pcbnew")
	(generator_version "10.0")
	(general
		(thickness 1.6)
		(legacy_teardrops no)
	)
	(paper "A4")
	(title_block
		(title "04192023_DAF0TMB3IC0_F0TG_MB_C_brd_V02_OCP.brd")
		(comment 1 "Grand Teton / footprints 670-670 of 8354")
	)
	(layers
		(0 "F.Cu" signal "TOP")
		(4 "In1.Cu" signal "GND")
		(6 "In2.Cu" signal "IN1")
		(8 "In3.Cu" signal "GND1")
		(10 "In4.Cu" signal "IN2")
		(12 "In5.Cu" signal "GND2")
		(14 "In6.Cu" signal "IN3")
		(16 "In7.Cu" signal "GND3")
		(18 "In8.Cu" signal "VCC")
		(20 "In9.Cu" signal "VCC1")
		(22 "In10.Cu" signal "GND4")
		(24 "In11.Cu" signal "IN4")
		(26 "In12.Cu" signal "GND5")
		(28 "In13.Cu" signal "IN5")
		(30 "In14.Cu" signal "GND6")
		(32 "In15.Cu" signal "IN6")
		(34 "In16.Cu" signal "GND7")
		(2 "B.Cu" signal "BOTTOM")
		(9 "F.Adhes" user "F.Adhesive")
		(11 "B.Adhes" user "B.Adhesive")
		(13 "F.Paste" user "Package Geometry/Pastemask Top")
		(15 "B.Paste" user "Package Geometry/Pastemask Bottom")
		(5 "F.SilkS" user "Ref Des/Silkscreen Top")
		(7 "B.SilkS" user "Ref Des/Silkscreen Bottom")
		(1 "F.Mask" user "Board Geometry/Soldermask Top")
		(3 "B.Mask" user "Board Geometry/Soldermask Bottom")
		(17 "Dwgs.User" user "User.Drawings")
		(19 "Cmts.User" user "User.Comments")
		(21 "Eco1.User" user "User.Eco1")
		(23 "Eco2.User" user "User.Eco2")
		(25 "Edge.Cuts" user "Board Geometry/Outline")
		(27 "Margin" user)
		(31 "F.CrtYd" user "Package Geometry/Place Bound Top")
		(29 "B.CrtYd" user "Package Geometry/Place Bound Bottom")
		(35 "F.Fab" user "Ref Des/Assembly Top")
		(33 "B.Fab" user "Ref Des/Assembly Bottom")
	)
	(footprint ""
		(layer "F.Cu")
		(at 97.745296 -412.931102 90)
		(property "Reference" "R4181"
			(at 0 0 90)
			(layer "F.SilkS")
			(hide yes)
			(effects
				(font
					(size 1.27 1.27)
				)
			)
		)
		(property "Value" ""
			(at 0 0 90)
			(layer "F.Fab")
			(effects
				(font
					(size 1.27 1.27)
				)
			)
		)
		(duplicate_pad_numbers_are_jumpers no)
		(fp_line
			(start 0.7874 -0.4064)
			(end 0.7874 0.4064)
			(stroke
				(width 0.1524)
				(type default)
			)
			(layer "F.SilkS")
		)
		(fp_line
			(start -0.7874 -0.4064)
			(end 0.7874 -0.4064)
			(stroke
				(width 0.1524)
				(type default)
			)
			(layer "F.SilkS")
		)
		(fp_line
			(start 0.7874 0.4064)
			(end -0.7874 0.4064)
			(stroke
				(width 0.1524)
				(type default)
			)
			(layer "F.SilkS")
		)
		(fp_line
			(start -0.7874 0.4064)
			(end -0.7874 -0.4064)
			(stroke
				(width 0.1524)
				(type default)
			)
			(layer "F.SilkS")
		)
		(fp_line
			(start -0.12065 -0.305054)
			(end -0.12065 -0.2794)
			(stroke
				(width 0.1)
				(type default)
			)
			(layer "F.Fab")
		)
		(fp_line
			(start -0.67945 -0.305054)
			(end -0.12065 -0.305054)
			(stroke
				(width 0.1)
				(type default)
			)
			(layer "F.Fab")
		)
		(fp_line
			(start 0.67945 -0.3048)
			(end 0.67945 0.3048)
			(stroke
				(width 0.1)
				(type default)
			)
			(layer "F.Fab")
		)
		(fp_line
			(start 0.12065 -0.3048)
			(end 0.67945 -0.3048)
			(stroke
				(width 0.1)
				(type default)
			)
			(layer "F.Fab")
		)
		(fp_line
			(start 0.12065 -0.2794)
			(end 0.12065 -0.3048)
			(stroke
				(width 0.1)
				(type default)
			)
			(layer "F.Fab")
		)
		(fp_line
			(start -0.12065 -0.2794)
			(end 0.12065 -0.2794)
			(stroke
				(width 0.1)
				(type default)
			)
			(layer "F.Fab")
		)
		(fp_line
			(start 0.120396 0.2794)
			(end -0.12065 0.2794)
			(stroke
				(width 0.1)
				(type default)
			)
			(layer "F.Fab")
		)
		(fp_line
			(start -0.12065 0.2794)
			(end -0.12065 0.3048)
			(stroke
				(width 0.1)
				(type default)
			)
			(layer "F.Fab")
		)
		(fp_line
			(start 0.67945 0.3048)
			(end 0.120396 0.3048)
			(stroke
				(width 0.1)
				(type default)
			)
			(layer "F.Fab")
		)
		(fp_line
			(start 0.120396 0.3048)
			(end 0.120396 0.2794)
			(stroke
				(width 0.1)
				(type default)
			)
			(layer "F.Fab")
		)
		(fp_line
			(start -0.12065 0.3048)
			(end -0.67945 0.3048)
			(stroke
				(width 0.1)
				(type default)
			)
			(layer "F.Fab")
		)
		(fp_line
			(start -0.67945 0.3048)
			(end -0.67945 -0.305054)
			(stroke
				(width 0.1)
				(type default)
			)
			(layer "F.Fab")
		)
		(pad "1" smd circle
			(at -0.40005 0 90)
			(size 0 0)
			(layers "F.Cu" "F.Mask" "F.Paste")
			(net "SMB_LM75_2_3V3AUX_SDA")
		)
		(pad "2" smd circle
			(at 0.40005 0 90)
			(size 0 0)
			(layers "F.Cu" "F.Mask" "F.Paste")
			(net "SMB_LM75_2_3V3AUX_SDA_R1")
		)
	)
)
